(kicad_pcb
	(version 20260206)
	(generator "pcbnew")
	(generator_version "10.0")
	(general
		(thickness 1.6)
		(legacy_teardrops no)
	)
	(paper "A4")
	(title_block
		(title "peb — Lightning_PEB_BRD.brd")
		(comment 1 "Lightning (Wiwynn / Facebook NVMe JBOF) / footprints 1216-1222 of 2563")
	)
	(layers
		(0 "F.Cu" signal "TOP")
		(4 "In1.Cu" signal "L2GND")
		(6 "In2.Cu" signal "L3")
		(8 "In3.Cu" signal "L4VCC")
		(10 "In4.Cu" signal "L5VCC")
		(12 "In5.Cu" signal "L6")
		(14 "In6.Cu" signal "L7GND")
		(2 "B.Cu" signal "BOTTOM")
		(9 "F.Adhes" user "F.Adhesive")
		(11 "B.Adhes" user "B.Adhesive")
		(13 "F.Paste" user "Package Geometry/Pastemask Top")
		(15 "B.Paste" user "Package Geometry/Pastemask Bottom")
		(5 "F.SilkS" user "Ref Des/Silkscreen Top")
		(7 "B.SilkS" user "Ref Des/Silkscreen Bottom")
		(1 "F.Mask" user "Board Geometry/Soldermask Top")
		(3 "B.Mask" user "Board Geometry/Soldermask Bottom")
		(17 "Dwgs.User" user "User.Drawings")
		(19 "Cmts.User" user "User.Comments")
		(21 "Eco1.User" user "User.Eco1")
		(23 "Eco2.User" user "User.Eco2")
		(25 "Edge.Cuts" user "Board Geometry/Outline")
		(27 "Margin" user)
		(31 "F.CrtYd" user "Package Geometry/Place Bound Top")
		(29 "B.CrtYd" user "Package Geometry/Place Bound Bottom")
		(35 "F.Fab" user "Ref Des/Assembly Top")
		(33 "B.Fab" user "Ref Des/Assembly Bottom")
	)
	(footprint ""
		(layer "F.Cu")
		(at 15.4432 -194.2592 180)
		(property "Reference" "R2174"
			(at 0 0 180)
			(layer "F.SilkS")
			(hide yes)
			(effects
				(font
					(size 1.27 1.27)
				)
			)
		)
		(property "Value" "100KR2J-4-GP"
			(at 0.064008 -3.993896 180)
			(unlocked yes)
			(layer "F.Fab")
			(hide yes)
			(effects
				(font
					(size 1.016 1.016)
					(thickness 0.1524)
				)
			)
		)
		(property "Device Type" "R402H15"
			(at 0.064008 -5.517896 180)
			(unlocked yes)
			(layer "F.Fab")
			(hide yes)
			(effects
				(font
					(size 1.016 1.016)
					(thickness 0.1524)
				)
			)
		)
		(duplicate_pad_numbers_are_jumpers no)
		(fp_line
			(start 0.508 -0.9398)
			(end -0.508 -0.9398)
			(stroke
				(width 0.1524)
				(type default)
			)
			(layer "F.SilkS")
		)
		(fp_line
			(start -0.508 -0.9398)
			(end -0.508 0.9398)
			(stroke
				(width 0.1524)
				(type default)
			)
			(layer "F.SilkS")
		)
		(fp_rect
			(start -0.508 0.9398)
			(end 0.508 -0.9398)
			(stroke
				(width 0)
				(type default)
			)
			(fill no)
			(layer "F.CrtYd")
		)
		(fp_rect
			(start -0.508 0.9398)
			(end 0.508 -0.9398)
			(stroke
				(width 0)
				(type default)
			)
			(fill no)
			(layer "F.Fab")
		)
		(pad "1" smd custom
			(at 0 -0.4445 180)
			(size 0.1397 0.1397)
			(layers "F.Cu" "F.Mask" "F.Paste")
			(net "MB0_VCAP_R")
			(options
				(clearance outline)
				(anchor circle)
			)
			(primitives
				(gr_poly
					(pts
						(arc
							(start -0.1778 -0.2794)
							(mid -0.249642 -0.249642)
							(end -0.2794 -0.1778)
						)
						(arc
							(start -0.2794 0.1778)
							(mid -0.249642 0.249642)
							(end -0.1778 0.2794)
						)
						(arc
							(start 0.1778 0.2794)
							(mid 0.249642 0.249642)
							(end 0.2794 0.1778)
						)
						(arc
							(start 0.2794 -0.1778)
							(mid 0.249642 -0.249642)
							(end 0.1778 -0.2794)
						)
					)
					(width 0)
					(fill yes)
				)
			)
		)
		(pad "2" smd custom
			(at 0 0.4445 180)
			(size 0.1397 0.1397)
			(layers "F.Cu" "F.Mask" "F.Paste")
			(net "MB0_ISTART_R")
			(options
				(clearance outline)
				(anchor circle)
			)
			(primitives
				(gr_poly
					(pts
						(arc
							(start -0.1778 -0.2794)
							(mid -0.249642 -0.249642)
							(end -0.2794 -0.1778)
						)
						(arc
							(start -0.2794 0.1778)
							(mid -0.249642 0.249642)
							(end -0.1778 0.2794)
						)
						(arc
							(start 0.1778 0.2794)
							(mid 0.249642 0.249642)
							(end 0.2794 0.1778)
						)
						(arc
							(start 0.2794 -0.1778)
							(mid 0.249642 -0.249642)
							(end 0.1778 -0.2794)
						)
					)
					(width 0)
					(fill yes)
				)
			)
		)
	)
	(footprint ""
		(layer "F.Cu")
		(at 23.876 -128.524 90)
		(property "Reference" "R365"
			(at 0 0 90)
			(layer "F.SilkS")
			(hide yes)
			(effects
				(font
					(size 1.27 1.27)
				)
			)
		)
		(property "Value" "3K3R2F-2-GP"
			(at 0.064008 -3.993896 90)
			(unlocked yes)
			(layer "F.Fab")
			(hide yes)
			(effects
				(font
					(size 1.016 1.016)
					(thickness 0.1524)
				)
			)
		)
		(property "Device Type" "R402H16"
			(at 0.064008 -5.517896 90)
			(unlocked yes)
			(layer "F.Fab")
			(hide yes)
			(effects
				(font
					(size 1.016 1.016)
					(thickness 0.1524)
				)
			)
		)
		(duplicate_pad_numbers_are_jumpers no)
		(fp_line
			(start 0.508 -0.9398)
			(end -0.508 -0.9398)
			(stroke
				(width 0.1524)
				(type default)
			)
			(layer "F.SilkS")
		)
		(fp_line
			(start -0.508 -0.9398)
			(end -0.508 0.9398)
			(stroke
				(width 0.1524)
				(type default)
			)
			(layer "F.SilkS")
		)
		(fp_rect
			(start -0.508 0.9398)
			(end 0.508 -0.9398)
			(stroke
				(width 0)
				(type default)
			)
			(fill no)
			(layer "F.CrtYd")
		)
		(fp_rect
			(start -0.508 0.9398)
			(end 0.508 -0.9398)
			(stroke
				(width 0)
				(type default)
			)
			(fill no)
			(layer "F.Fab")
		)
		(pad "1" smd custom
			(at 0 -0.4445 90)
			(size 0.1397 0.1397)
			(layers "F.Cu" "F.Mask" "F.Paste")
			(net "P3V3_STBY")
			(options
				(clearance outline)
				(anchor circle)
			)
			(primitives
				(gr_poly
					(pts
						(arc
							(start -0.1778 -0.2794)
							(mid -0.249642 -0.249642)
							(end -0.2794 -0.1778)
						)
						(arc
							(start -0.2794 0.1778)
							(mid -0.249642 0.249642)
							(end -0.1778 0.2794)
						)
						(arc
							(start 0.1778 0.2794)
							(mid 0.249642 0.249642)
							(end 0.2794 0.1778)
						)
						(arc
							(start 0.2794 -0.1778)
							(mid 0.249642 -0.249642)
							(end 0.1778 -0.2794)
						)
					)
					(width 0)
					(fill yes)
				)
			)
		)
		(pad "2" smd custom
			(at 0 0.4445 90)
			(size 0.1397 0.1397)
			(layers "F.Cu" "F.Mask" "F.Paste")
			(net "ROMA22")
			(options
				(clearance outline)
				(anchor circle)
			)
			(primitives
				(gr_poly
					(pts
						(arc
							(start -0.1778 -0.2794)
							(mid -0.249642 -0.249642)
							(end -0.2794 -0.1778)
						)
						(arc
							(start -0.2794 0.1778)
							(mid -0.249642 0.249642)
							(end -0.1778 0.2794)
						)
						(arc
							(start 0.1778 0.2794)
							(mid 0.249642 0.249642)
							(end 0.2794 0.1778)
						)
						(arc
							(start 0.2794 -0.1778)
							(mid 0.249642 -0.249642)
							(end 0.1778 -0.2794)
						)
					)
					(width 0)
					(fill yes)
				)
			)
		)
	)
	(footprint ""
		(layer "F.Cu")
		(at 73.7108 -180.1622 180)
		(property "Reference" "C4104"
			(at 0 0 180)
			(layer "F.SilkS")
			(hide yes)
			(effects
				(font
					(size 1.27 1.27)
				)
			)
		)
		(property "Value" "SCD1U25V3KX-GP"
			(at 0 -2.8194 180)
			(unlocked yes)
			(layer "F.Fab")
			(hide yes)
			(effects
				(font
					(size 1.016 1.016)
					(thickness 0.1524)
				)
			)
		)
		(property "Device Type" "C603H36"
			(at 0 -4.3434 180)
			(unlocked yes)
			(layer "F.Fab")
			(hide yes)
			(effects
				(font
					(size 1.016 1.016)
					(thickness 0.1524)
				)
			)
		)
		(duplicate_pad_numbers_are_jumpers no)
		(fp_line
			(start 0.508 0)
			(end -0.508 0)
			(stroke
				(width 0.2032)
				(type default)
			)
			(layer "F.SilkS")
		)
		(fp_rect
			(start -0.5842 1.3335)
			(end 0.5842 -1.3335)
			(stroke
				(width 0)
				(type default)
			)
			(fill no)
			(layer "F.CrtYd")
		)
		(fp_rect
			(start -0.5842 1.3335)
			(end 0.5842 -1.3335)
			(stroke
				(width 0)
				(type default)
			)
			(fill no)
			(layer "F.Fab")
		)
		(pad "1" smd custom
			(at 0 -0.762 180)
			(size 0.2159 0.2159)
			(layers "F.Cu" "F.Mask" "F.Paste")
			(net "GND")
			(options
				(clearance outline)
				(anchor circle)
			)
			(primitives
				(gr_poly
					(pts
						(arc
							(start -0.3302 -0.4318)
							(mid -0.402042 -0.402042)
							(end -0.4318 -0.3302)
						)
						(arc
							(start -0.4318 0.3302)
							(mid -0.402042 0.402042)
							(end -0.3302 0.4318)
						)
						(arc
							(start 0.3302 0.4318)
							(mid 0.402042 0.402042)
							(end 0.4318 0.3302)
						)
						(arc
							(start 0.4318 -0.3302)
							(mid 0.402042 -0.402042)
							(end 0.3302 -0.4318)
						)
					)
					(width 0)
					(fill yes)
				)
			)
		)
		(pad "2" smd custom
			(at 0 0.762 180)
			(size 0.2159 0.2159)
			(layers "F.Cu" "F.Mask" "F.Paste")
			(net "SSD_PWREN0_R")
			(options
				(clearance outline)
				(anchor circle)
			)
			(primitives
				(gr_poly
					(pts
						(arc
							(start -0.3302 -0.4318)
							(mid -0.402042 -0.402042)
							(end -0.4318 -0.3302)
						)
						(arc
							(start -0.4318 0.3302)
							(mid -0.402042 0.402042)
							(end -0.3302 0.4318)
						)
						(arc
							(start 0.3302 0.4318)
							(mid 0.402042 0.402042)
							(end 0.4318 0.3302)
						)
						(arc
							(start 0.4318 -0.3302)
							(mid 0.402042 -0.402042)
							(end 0.3302 -0.4318)
						)
					)
					(width 0)
					(fill yes)
				)
			)
		)
	)
	(footprint ""
		(layer "F.Cu")
		(at 13.5128 -118.9736)
		(property "Reference" "R600"
			(at 0 0 0)
			(layer "F.SilkS")
			(hide yes)
			(effects
				(font
					(size 1.27 1.27)
				)
			)
		)
		(property "Value" "4K7R2F-GP"
			(at 0.064008 -3.993896 0)
			(unlocked yes)
			(layer "F.Fab")
			(hide yes)
			(effects
				(font
					(size 1.016 1.016)
					(thickness 0.1524)
				)
			)
		)
		(property "Device Type" "R402H16"
			(at 0.064008 -5.517896 0)
			(unlocked yes)
			(layer "F.Fab")
			(hide yes)
			(effects
				(font
					(size 1.016 1.016)
					(thickness 0.1524)
				)
			)
		)
		(duplicate_pad_numbers_are_jumpers no)
		(fp_line
			(start -0.508 -0.9398)
			(end -0.508 0.9398)
			(stroke
				(width 0.1524)
				(type default)
			)
			(layer "F.SilkS")
		)
		(fp_line
			(start 0.508 -0.9398)
			(end -0.508 -0.9398)
			(stroke
				(width 0.1524)
				(type default)
			)
			(layer "F.SilkS")
		)
		(fp_rect
			(start -0.508 0.9398)
			(end 0.508 -0.9398)
			(stroke
				(width 0)
				(type default)
			)
			(fill no)
			(layer "F.CrtYd")
		)
		(fp_rect
			(start -0.508 0.9398)
			(end 0.508 -0.9398)
			(stroke
				(width 0)
				(type default)
			)
			(fill no)
			(layer "F.Fab")
		)
		(pad "1" smd custom
			(at 0 -0.4445)
			(size 0.1397 0.1397)
			(layers "F.Cu" "F.Mask" "F.Paste")
			(net "BMC_I2C1_MINI1_SDA_S")
			(options
				(clearance outline)
				(anchor circle)
			)
			(primitives
				(gr_poly
					(pts
						(arc
							(start -0.1778 -0.2794)
							(mid -0.249642 -0.249642)
							(end -0.2794 -0.1778)
						)
						(arc
							(start -0.2794 0.1778)
							(mid -0.249642 0.249642)
							(end -0.1778 0.2794)
						)
						(arc
							(start 0.1778 0.2794)
							(mid 0.249642 0.249642)
							(end 0.2794 0.1778)
						)
						(arc
							(start 0.2794 -0.1778)
							(mid 0.249642 -0.249642)
							(end 0.1778 -0.2794)
						)
					)
					(width 0)
					(fill yes)
				)
			)
		)
		(pad "2" smd custom
			(at 0 0.4445)
			(size 0.1397 0.1397)
			(layers "F.Cu" "F.Mask" "F.Paste")
			(net "P3V3_STBY")
			(options
				(clearance outline)
				(anchor circle)
			)
			(primitives
				(gr_poly
					(pts
						(arc
							(start -0.1778 -0.2794)
							(mid -0.249642 -0.249642)
							(end -0.2794 -0.1778)
						)
						(arc
							(start -0.2794 0.1778)
							(mid -0.249642 0.249642)
							(end -0.1778 0.2794)
						)
						(arc
							(start 0.1778 0.2794)
							(mid 0.249642 0.249642)
							(end 0.2794 0.1778)
						)
						(arc
							(start 0.2794 -0.1778)
							(mid 0.249642 -0.249642)
							(end 0.1778 -0.2794)
						)
					)
					(width 0)
					(fill yes)
				)
			)
		)
	)
	(footprint ""
		(layer "F.Cu")
		(at 15.875 -182.2196 90)
		(property "Reference" "P2121"
			(at 0 0 90)
			(layer "F.SilkS")
			(hide yes)
			(effects
				(font
					(size 1.27 1.27)
				)
			)
		)
		(property "Value" "0R0603-PAD-2-GP-U"
			(at 2.1209 -0.1397 90)
			(unlocked yes)
			(layer "F.Fab")
			(hide yes)
			(effects
				(font
					(size 1.016 1.016)
					(thickness 0.1524)
				)
			)
		)
		(property "Device Type" "0R0603-PAD-1-U"
			(at 2.1209 -1.6637 90)
			(unlocked yes)
			(layer "F.Fab")
			(hide yes)
			(effects
				(font
					(size 1.016 1.016)
					(thickness 0.1524)
				)
			)
		)
		(duplicate_pad_numbers_are_jumpers no)
		(fp_rect
			(start -0.5842 1.3335)
			(end 0.5842 -1.3335)
			(stroke
				(width 0)
				(type default)
			)
			(fill no)
			(layer "F.CrtYd")
		)
		(fp_rect
			(start -0.5842 1.3335)
			(end 0.5842 -1.3335)
			(stroke
				(width 0)
				(type default)
			)
			(fill no)
			(layer "F.Fab")
		)
		(pad "1" smd custom
			(at 0 -0.762 90)
			(size 0.2159 0.2159)
			(layers "F.Cu" "F.Mask" "F.Paste")
			(net "AGND_CURRENT_MON")
			(options
				(clearance outline)
				(anchor circle)
			)
			(primitives
				(gr_poly
					(pts
						(arc
							(start -0.3302 -0.5842)
							(mid -0.402042 -0.554442)
							(end -0.4318 -0.4826)
						)
						(arc
							(start -0.4318 0.4826)
							(mid -0.402042 0.554442)
							(end -0.3302 0.5842)
						)
						(arc
							(start 0.3302 0.5842)
							(mid 0.402042 0.554442)
							(end 0.4318 0.4826)
						)
						(arc
							(start 0.4318 -0.4826)
							(mid 0.402042 -0.554442)
							(end 0.3302 -0.5842)
						)
					)
					(width 0)
					(fill yes)
				)
			)
		)
		(pad "2" smd custom
			(at 0 0.762 90)
			(size 0.2159 0.2159)
			(layers "F.Cu" "F.Mask" "F.Paste")
			(net "GND")
			(options
				(clearance outline)
				(anchor circle)
			)
			(primitives
				(gr_poly
					(pts
						(arc
							(start -0.4318 0.4826)
							(mid -0.402042 0.554442)
							(end -0.3302 0.5842)
						)
						(arc
							(start 0.3302 0.5842)
							(mid 0.402042 0.554442)
							(end 0.4318 0.4826)
						)
						(arc
							(start 0.4318 -0.4826)
							(mid 0.402042 -0.554442)
							(end 0.3302 -0.5842)
						)
						(arc
							(start -0.3302 -0.5842)
							(mid -0.402042 -0.554442)
							(end -0.4318 -0.4826)
						)
					)
					(width 0)
					(fill yes)
				)
			)
		)
	)
	(footprint ""
		(layer "F.Cu")
		(at 51.591972 -212.420454 180)
		(property "Reference" "C363"
			(at 0 0 180)
			(layer "F.SilkS")
			(hide yes)
			(effects
				(font
					(size 1.27 1.27)
				)
			)
		)
		(property "Value" "SCD22U10V2KX-1GP"
			(at 1.1811 -2.7051 180)
			(unlocked yes)
			(layer "F.Fab")
			(hide yes)
			(effects
				(font
					(size 1.016 1.016)
					(thickness 0.1524)
				)
			)
		)
		(property "Device Type" "C402H22"
			(at 1.1811 -4.2291 180)
			(unlocked yes)
			(layer "F.Fab")
			(hide yes)
			(effects
				(font
					(size 1.016 1.016)
					(thickness 0.1524)
				)
			)
		)
		(duplicate_pad_numbers_are_jumpers no)
		(fp_rect
			(start -0.4318 0.9525)
			(end 0.4318 -0.9525)
			(stroke
				(width 0)
				(type default)
			)
			(fill no)
			(layer "F.CrtYd")
		)
		(fp_rect
			(start -0.4318 0.9525)
			(end 0.4318 -0.9525)
			(stroke
				(width 0)
				(type default)
			)
			(fill no)
			(layer "F.Fab")
		)
		(pad "1" smd custom
			(at 0 -0.4445 180)
			(size 0.1524 0.1524)
			(layers "F.Cu" "F.Mask" "F.Paste")
			(net "PCIE_TX_CAP_P74")
			(options
				(clearance outline)
				(anchor circle)
			)
			(primitives
				(gr_poly
					(pts
						(arc
							(start 0.3048 -0.2032)
							(mid 0.275042 -0.275042)
							(end 0.2032 -0.3048)
						)
						(arc
							(start -0.2032 -0.3048)
							(mid -0.275042 -0.275042)
							(end -0.3048 -0.2032)
						)
						(arc
							(start -0.3048 0.2032)
							(mid -0.275042 0.275042)
							(end -0.2032 0.3048)
						)
						(arc
							(start 0.2032 0.3048)
							(mid 0.275042 0.275042)
							(end 0.3048 0.2032)
						)
					)
					(width 0)
					(fill yes)
				)
			)
		)
		(pad "2" smd custom
			(at 0 0.4445 180)
			(size 0.1524 0.1524)
			(layers "F.Cu" "F.Mask" "F.Paste")
			(net "PCIE_TX_P74")
			(options
				(clearance outline)
				(anchor circle)
			)
			(primitives
				(gr_poly
					(pts
						(arc
							(start 0.3048 -0.2032)
							(mid 0.275042 -0.275042)
							(end 0.2032 -0.3048)
						)
						(arc
							(start -0.2032 -0.3048)
							(mid -0.275042 -0.275042)
							(end -0.3048 -0.2032)
						)
						(arc
							(start -0.3048 0.2032)
							(mid -0.275042 0.275042)
							(end -0.2032 0.3048)
						)
						(arc
							(start 0.2032 0.3048)
							(mid 0.275042 0.275042)
							(end 0.3048 0.2032)
						)
					)
					(width 0)
					(fill yes)
				)
			)
		)
	)
	(footprint ""
		(layer "F.Cu")
		(at 11.176 -71.3486 -90)
		(property "Reference" "R386"
			(at 0 0 270)
			(layer "F.SilkS")
			(hide yes)
			(effects
				(font
					(size 1.27 1.27)
				)
			)
		)
		(property "Value" "0R2J-2-GP"
			(at 0.064008 -3.993896 270)
			(unlocked yes)
			(layer "F.Fab")
			(hide yes)
			(effects
				(font
					(size 1.016 1.016)
					(thickness 0.1524)
				)
			)
		)
		(property "Device Type" "R402H16"
			(at 0.064008 -5.517896 270)
			(unlocked yes)
			(layer "F.Fab")
			(hide yes)
			(effects
				(font
					(size 1.016 1.016)
					(thickness 0.1524)
				)
			)
		)
		(duplicate_pad_numbers_are_jumpers no)
		(fp_line
			(start -0.508 -0.9398)
			(end -0.508 0.9398)
			(stroke
				(width 0.1524)
				(type default)
			)
			(layer "F.SilkS")
		)
		(fp_line
			(start 0.508 -0.9398)
			(end -0.508 -0.9398)
			(stroke
				(width 0.1524)
				(type default)
			)
			(layer "F.SilkS")
		)
		(fp_rect
			(start -0.508 0.9398)
			(end 0.508 -0.9398)
			(stroke
				(width 0)
				(type default)
			)
			(fill no)
			(layer "F.CrtYd")
		)
		(fp_rect
			(start -0.508 0.9398)
			(end 0.508 -0.9398)
			(stroke
				(width 0)
				(type default)
			)
			(fill no)
			(layer "F.Fab")
		)
		(pad "1" smd custom
			(at 0 -0.4445 270)
			(size 0.1397 0.1397)
			(layers "F.Cu" "F.Mask" "F.Paste")
			(net "XTAL_OUT_I210")
			(options
				(clearance outline)
				(anchor circle)
			)
			(primitives
				(gr_poly
					(pts
						(arc
							(start -0.1778 -0.2794)
							(mid -0.249642 -0.249642)
							(end -0.2794 -0.1778)
						)
						(arc
							(start -0.2794 0.1778)
							(mid -0.249642 0.249642)
							(end -0.1778 0.2794)
						)
						(arc
							(start 0.1778 0.2794)
							(mid 0.249642 0.249642)
							(end 0.2794 0.1778)
						)
						(arc
							(start 0.2794 -0.1778)
							(mid 0.249642 -0.249642)
							(end 0.1778 -0.2794)
						)
					)
					(width 0)
					(fill yes)
				)
			)
		)
		(pad "2" smd custom
			(at 0 0.4445 270)
			(size 0.1397 0.1397)
			(layers "F.Cu" "F.Mask" "F.Paste")
			(net "XTAL_OUT_I210_R")
			(options
				(clearance outline)
				(anchor circle)
			)
			(primitives
				(gr_poly
					(pts
						(arc
							(start -0.1778 -0.2794)
							(mid -0.249642 -0.249642)
							(end -0.2794 -0.1778)
						)
						(arc
							(start -0.2794 0.1778)
							(mid -0.249642 0.249642)
							(end -0.1778 0.2794)
						)
						(arc
							(start 0.1778 0.2794)
							(mid 0.249642 0.249642)
							(end 0.2794 0.1778)
						)
						(arc
							(start 0.2794 -0.1778)
							(mid 0.249642 -0.249642)
							(end 0.1778 -0.2794)
						)
					)
					(width 0)
					(fill yes)
				)
			)
		)
	)
)
